# BASEBOARD_FAB2 (Tioga Pass) — schematic netlist excerpt (pin names and nets, part order shuffled) for the footprints in the layout excerpt that follows; sources: Cadence DE-HDL packaged netlist, KiCad conversion of Wiwynn_Tioga_Pass_MB.brd

C5T12  CAP_A  47UF 4V 20% X5R  pkg 0603V  page 217 : A = PVDDQ_ABC ; B = GND
C5U6  CAP_A  47UF 4V 20% X5R  pkg 0603V  page 217 : A = PVDDQ_ABC ; B = GND

(kicad_pcb
	(version 20260206)
	(generator "pcbnew")
	(generator_version "10.0")
	(general
		(thickness 1.6)
		(legacy_teardrops no)
	)
	(paper "A4")
	(title_block
		(title "Wiwynn_Tioga_Pass_MB.brd")
		(comment 1 "Tioga Pass / footprints 3252-3253 of 4770")
	)
	(layers
		(0 "F.Cu" signal "TOP")
		(4 "In1.Cu" signal "L2GND")
		(6 "In2.Cu" signal "L3")
		(8 "In3.Cu" signal "L4GND")
		(10 "In4.Cu" signal "L5")
		(12 "In5.Cu" signal "L6GND")
		(14 "In6.Cu" signal "L7VCC")
		(16 "In7.Cu" signal "L8VCC")
		(18 "In8.Cu" signal "L9GND")
		(20 "In9.Cu" signal "L10")
		(22 "In10.Cu" signal "L11GND")
		(24 "In11.Cu" signal "L12")
		(26 "In12.Cu" signal "L13GND")
		(2 "B.Cu" signal "BOTTOM")
		(9 "F.Adhes" user "F.Adhesive")
		(11 "B.Adhes" user "B.Adhesive")
		(13 "F.Paste" user "Package Geometry/Pastemask Top")
		(15 "B.Paste" user "Package Geometry/Pastemask Bottom")
		(5 "F.SilkS" user "Ref Des/Silkscreen Top")
		(7 "B.SilkS" user "Ref Des/Silkscreen Bottom")
		(1 "F.Mask" user "Board Geometry/Soldermask Top")
		(3 "B.Mask" user "Board Geometry/Soldermask Bottom")
		(17 "Dwgs.User" user "User.Drawings")
		(19 "Cmts.User" user "User.Comments")
		(21 "Eco1.User" user "User.Eco1")
		(23 "Eco2.User" user "User.Eco2")
		(25 "Edge.Cuts" user "Board Geometry/Outline")
		(27 "Margin" user)
		(31 "F.CrtYd" user "Package Geometry/Place Bound Top")
		(29 "B.CrtYd" user "Package Geometry/Place Bound Bottom")
		(35 "F.Fab" user "Ref Des/Assembly Top")
		(33 "B.Fab" user "Ref Des/Assembly Bottom")
	)
	(footprint ""
		(layer "B.Cu")
		(at 245.7577 -17.7546 -90)
		(property "Reference" "C5T12"
			(at -1.848866 0.752348 270)
			(unlocked yes)
			(layer "B.SilkS")
			(effects
				(font
					(size 1.27 0.9652)
					(thickness 0.1524)
				)
				(justify mirror)
			)
		)
		(property "Value" ""
			(at 0 0 90)
			(layer "B.Fab")
			(effects
				(font
					(size 1.27 1.27)
				)
				(justify mirror)
			)
		)
		(duplicate_pad_numbers_are_jumpers no)
		(fp_rect
			(start 0.500126 1.598422)
			(end -0.500126 -0.201422)
			(stroke
				(width 0)
				(type default)
			)
			(fill no)
			(layer "B.CrtYd")
		)
		(fp_line
			(start -0.500126 1.598422)
			(end 0.500126 1.598422)
			(stroke
				(width 0.1)
				(type default)
			)
			(layer "B.Fab")
		)
		(fp_line
			(start 0.500126 1.598422)
			(end 0.500126 -0.201422)
			(stroke
				(width 0.1)
				(type default)
			)
			(layer "B.Fab")
		)
		(fp_line
			(start -0.500126 -0.201422)
			(end -0.500126 1.598422)
			(stroke
				(width 0.1)
				(type default)
			)
			(layer "B.Fab")
		)
		(fp_line
			(start 0.500126 -0.201422)
			(end -0.500126 -0.201422)
			(stroke
				(width 0.1)
				(type default)
			)
			(layer "B.Fab")
		)
		(pad "1" smd rect
			(at 0 0 180)
			(size 0.889 0.9906)
			(layers "B.Cu" "B.Mask" "B.Paste")
			(net "PVDDQ_ABC")
		)
		(pad "2" smd rect
			(at 0 1.397 180)
			(size 0.889 0.9906)
			(layers "B.Cu" "B.Mask" "B.Paste")
			(net "GND")
		)
		(zone
			(layer "B.Cu")
			(hatch none 0.5)
			(connect_pads
				(clearance 0)
			)
			(min_thickness 0.25)
			(keepout
				(tracks not_allowed)
				(vias allowed)
				(pads allowed)
				(copperpour not_allowed)
				(footprints allowed)
			)
			(placement
				(enabled no)
				(sheetname "")
			)
			(fill
				(thermal_gap 0.5)
				(thermal_bridge_width 0.5)
				(island_removal_mode 0)
			)
			(polygon
				(pts
					(xy 244.8052 -17.2593) (xy 245.3132 -17.2593) (xy 245.3132 -18.2499) (xy 244.8052 -18.2499)
				)
			)
		)
		(zone
			(layer "B.Cu")
			(hatch none 0.5)
			(connect_pads
				(clearance 0)
			)
			(min_thickness 0.25)
			(keepout
				(tracks allowed)
				(vias not_allowed)
				(pads allowed)
				(copperpour not_allowed)
				(footprints allowed)
			)
			(placement
				(enabled no)
				(sheetname "")
			)
			(fill
				(thermal_gap 0.5)
				(thermal_bridge_width 0.5)
				(island_removal_mode 0)
			)
			(polygon
				(pts
					(xy 244.8052 -17.2593) (xy 245.3132 -17.2593) (xy 245.3132 -18.2499) (xy 244.8052 -18.2499)
				)
			)
		)
	)
	(footprint ""
		(layer "B.Cu")
		(at 253.392432 -8.1534 90)
		(property "Reference" "C5U6"
			(at -1.848866 0.752348 90)
			(unlocked yes)
			(layer "B.SilkS")
			(effects
				(font
					(size 1.27 0.9652)
					(thickness 0.1524)
				)
				(justify mirror)
			)
		)
		(property "Value" ""
			(at 0 0 90)
			(layer "B.Fab")
			(effects
				(font
					(size 1.27 1.27)
				)
				(justify mirror)
			)
		)
		(duplicate_pad_numbers_are_jumpers no)
		(fp_rect
			(start 0.500126 1.598422)
			(end -0.500126 -0.201422)
			(stroke
				(width 0)
				(type default)
			)
			(fill no)
			(layer "B.CrtYd")
		)
		(fp_line
			(start 0.500126 -0.201422)
			(end -0.500126 -0.201422)
			(stroke
				(width 0.1)
				(type default)
			)
			(layer "B.Fab")
		)
		(fp_line
			(start -0.500126 -0.201422)
			(end -0.500126 1.598422)
			(stroke
				(width 0.1)
				(type default)
			)
			(layer "B.Fab")
		)
		(fp_line
			(start 0.500126 1.598422)
			(end 0.500126 -0.201422)
			(stroke
				(width 0.1)
				(type default)
			)
			(layer "B.Fab")
		)
		(fp_line
			(start -0.500126 1.598422)
			(end 0.500126 1.598422)
			(stroke
				(width 0.1)
				(type default)
			)
			(layer "B.Fab")
		)
		(pad "1" smd rect
			(at 0 0)
			(size 0.889 0.9906)
			(layers "B.Cu" "B.Mask" "B.Paste")
			(net "PVDDQ_ABC")
		)
		(pad "2" smd rect
			(at 0 1.397)
			(size 0.889 0.9906)
			(layers "B.Cu" "B.Mask" "B.Paste")
			(net "GND")
		)
		(zone
			(layer "B.Cu")
			(hatch none 0.5)
			(connect_pads
				(clearance 0)
			)
			(min_thickness 0.25)
			(keepout
				(tracks not_allowed)
				(vias allowed)
				(pads allowed)
				(copperpour not_allowed)
				(footprints allowed)
			)
			(placement
				(enabled no)
				(sheetname "")
			)
			(fill
				(thermal_gap 0.5)
				(thermal_bridge_width 0.5)
				(island_removal_mode 0)
			)
			(polygon
				(pts
					(xy 254.344932 -8.6487) (xy 253.836932 -8.6487) (xy 253.836932 -7.6581) (xy 254.344932 -7.6581)
				)
			)
		)
		(zone
			(layer "B.Cu")
			(hatch none 0.5)
			(connect_pads
				(clearance 0)
			)
			(min_thickness 0.25)
			(keepout
				(tracks allowed)
				(vias not_allowed)
				(pads allowed)
				(copperpour not_allowed)
				(footprints allowed)
			)
			(placement
				(enabled no)
				(sheetname "")
			)
			(fill
				(thermal_gap 0.5)
				(thermal_bridge_width 0.5)
				(island_removal_mode 0)
			)
			(polygon
				(pts
					(xy 254.344932 -8.6487) (xy 253.836932 -8.6487) (xy 253.836932 -7.6581) (xy 254.344932 -7.6581)
				)
			)
		)
	)
)
